(kicad_pcb
	(version 20260206)
	(generator "pcbnew")
	(generator_version "10.0")
	(general
		(thickness 1.6)
		(legacy_teardrops no)
	)
	(paper "A4")
	(title_block
		(title "03242023_DA0F0TMBIJ0_F0T_Motherboard_J_brd_V01_OCP.brd")
		(comment 1 "Grand Teton / footprints 6063-6068 of 6105")
	)
	(layers
		(0 "F.Cu" signal "TOP")
		(4 "In1.Cu" signal "GND")
		(6 "In2.Cu" signal "IN1")
		(8 "In3.Cu" signal "GND1")
		(10 "In4.Cu" signal "IN2")
		(12 "In5.Cu" signal "GND2")
		(14 "In6.Cu" signal "IN3")
		(16 "In7.Cu" signal "GND3")
		(18 "In8.Cu" signal "VCC")
		(20 "In9.Cu" signal "VCC1")
		(22 "In10.Cu" signal "GND4")
		(24 "In11.Cu" signal "IN4")
		(26 "In12.Cu" signal "GND5")
		(28 "In13.Cu" signal "IN5")
		(30 "In14.Cu" signal "GND6")
		(32 "In15.Cu" signal "IN6")
		(34 "In16.Cu" signal "GND7")
		(2 "B.Cu" signal "BOTTOM")
		(9 "F.Adhes" user "F.Adhesive")
		(11 "B.Adhes" user "B.Adhesive")
		(13 "F.Paste" user "Package Geometry/Pastemask Top")
		(15 "B.Paste" user "Package Geometry/Pastemask Bottom")
		(5 "F.SilkS" user "Ref Des/Silkscreen Top")
		(7 "B.SilkS" user "Ref Des/Silkscreen Bottom")
		(1 "F.Mask" user "Board Geometry/Soldermask Top")
		(3 "B.Mask" user "Board Geometry/Soldermask Bottom")
		(17 "Dwgs.User" user "User.Drawings")
		(19 "Cmts.User" user "User.Comments")
		(21 "Eco1.User" user "User.Eco1")
		(23 "Eco2.User" user "User.Eco2")
		(25 "Edge.Cuts" user "Board Geometry/Outline")
		(27 "Margin" user)
		(31 "F.CrtYd" user "Package Geometry/Place Bound Top")
		(29 "B.CrtYd" user "Package Geometry/Place Bound Bottom")
		(35 "F.Fab" user "Ref Des/Assembly Top")
		(33 "B.Fab" user "Ref Des/Assembly Bottom")
	)
	(footprint ""
		(layer "B.Cu")
		(at 171.21632 -13.762228 90)
		(property "Reference" "R4535"
			(at 0 0 90)
			(layer "B.SilkS")
			(hide yes)
			(effects
				(font
					(size 1.27 1.27)
				)
				(justify mirror)
			)
		)
		(property "Value" ""
			(at 0 0 90)
			(layer "B.Fab")
			(effects
				(font
					(size 1.27 1.27)
				)
				(justify mirror)
			)
		)
		(duplicate_pad_numbers_are_jumpers no)
		(fp_line
			(start 0.4064 -0.4064)
			(end -0.11176 -0.4064)
			(stroke
				(width 0.1524)
				(type default)
			)
			(layer "B.SilkS")
		)
		(fp_line
			(start -0.7874 -0.16002)
			(end -0.7874 0.4064)
			(stroke
				(width 0.1524)
				(type default)
			)
			(layer "B.SilkS")
		)
		(fp_line
			(start 0.7874 0.4064)
			(end 0.7874 -0.0508)
			(stroke
				(width 0.1524)
				(type default)
			)
			(layer "B.SilkS")
		)
		(fp_line
			(start -0.7874 0.4064)
			(end 0.7874 0.4064)
			(stroke
				(width 0.1524)
				(type default)
			)
			(layer "B.SilkS")
		)
		(fp_line
			(start 0.67945 -0.305054)
			(end 0.12065 -0.305054)
			(stroke
				(width 0.1)
				(type default)
			)
			(layer "B.Fab")
		)
		(fp_line
			(start 0.12065 -0.305054)
			(end 0.12065 -0.2794)
			(stroke
				(width 0.1)
				(type default)
			)
			(layer "B.Fab")
		)
		(fp_line
			(start -0.12065 -0.3048)
			(end -0.67945 -0.3048)
			(stroke
				(width 0.1)
				(type default)
			)
			(layer "B.Fab")
		)
		(fp_line
			(start -0.67945 -0.3048)
			(end -0.67945 0.3048)
			(stroke
				(width 0.1)
				(type default)
			)
			(layer "B.Fab")
		)
		(fp_line
			(start 0.12065 -0.2794)
			(end -0.12065 -0.2794)
			(stroke
				(width 0.1)
				(type default)
			)
			(layer "B.Fab")
		)
		(fp_line
			(start -0.12065 -0.2794)
			(end -0.12065 -0.3048)
			(stroke
				(width 0.1)
				(type default)
			)
			(layer "B.Fab")
		)
		(fp_line
			(start 0.12065 0.2794)
			(end 0.12065 0.3048)
			(stroke
				(width 0.1)
				(type default)
			)
			(layer "B.Fab")
		)
		(fp_line
			(start -0.120396 0.2794)
			(end 0.12065 0.2794)
			(stroke
				(width 0.1)
				(type default)
			)
			(layer "B.Fab")
		)
		(fp_line
			(start 0.67945 0.3048)
			(end 0.67945 -0.305054)
			(stroke
				(width 0.1)
				(type default)
			)
			(layer "B.Fab")
		)
		(fp_line
			(start 0.12065 0.3048)
			(end 0.67945 0.3048)
			(stroke
				(width 0.1)
				(type default)
			)
			(layer "B.Fab")
		)
		(fp_line
			(start -0.120396 0.3048)
			(end -0.120396 0.2794)
			(stroke
				(width 0.1)
				(type default)
			)
			(layer "B.Fab")
		)
		(fp_line
			(start -0.67945 0.3048)
			(end -0.120396 0.3048)
			(stroke
				(width 0.1)
				(type default)
			)
			(layer "B.Fab")
		)
		(pad "1" smd circle
			(at 0.40005 0 270)
			(size 0 0)
			(layers "B.Cu" "B.Mask" "B.Paste")
			(net "CLK_100M_BMC_P3E_DP")
		)
		(pad "2" smd circle
			(at -0.40005 0 270)
			(size 0 0)
			(layers "B.Cu" "B.Mask" "B.Paste")
			(net "CLK_100M_BMC_P3E_DP_R")
		)
	)
	(footprint ""
		(layer "B.Cu")
		(at 517.258808 -148.1328 -90)
		(property "Reference" "X23"
			(at 3.671824 3.308096 270)
			(unlocked yes)
			(layer "B.SilkS")
			(effects
				(font
					(size 0.7874 0.5842)
					(thickness 0.1524)
				)
				(justify left mirror)
			)
		)
		(property "Value" ""
			(at 0 0 90)
			(layer "B.Fab")
			(effects
				(font
					(size 1.27 1.27)
				)
				(justify mirror)
			)
		)
		(property "Device Type" "TP_TDR_4P_FTS_TH-TP_TDR_4P_DIPA"
			(at -1.30175 1.27 180)
			(unlocked yes)
			(layer "B.Fab")
			(hide yes)
			(effects
				(font
					(size 0.635 0.4064)
					(thickness 0.1524)
				)
				(justify mirror)
			)
		)
		(property "User Part Number" "N_A"
			(at -1.30175 1.27 180)
			(unlocked yes)
			(layer "Cmts.User")
			(hide yes)
			(effects
				(font
					(size 0.635 0.4064)
					(thickness 0.1524)
				)
				(justify mirror)
			)
		)
		(duplicate_pad_numbers_are_jumpers no)
		(fp_line
			(start -2.54 3.81)
			(end -2.54 3.6703)
			(stroke
				(width 0.1524)
				(type default)
			)
			(layer "B.SilkS")
		)
		(fp_line
			(start 0 3.81)
			(end -2.54 3.81)
			(stroke
				(width 0.1524)
				(type default)
			)
			(layer "B.SilkS")
		)
		(fp_line
			(start 0 3.175)
			(end 0 3.81)
			(stroke
				(width 0.1524)
				(type default)
			)
			(layer "B.SilkS")
		)
		(fp_line
			(start -2.54 1.4097)
			(end -2.54 1.1303)
			(stroke
				(width 0.1524)
				(type default)
			)
			(layer "B.SilkS")
		)
		(fp_line
			(start 0 0.635)
			(end 0 1.905)
			(stroke
				(width 0.1524)
				(type default)
			)
			(layer "B.SilkS")
		)
		(fp_line
			(start -2.54 -1.1303)
			(end -2.54 -1.27)
			(stroke
				(width 0.1524)
				(type default)
			)
			(layer "B.SilkS")
		)
		(fp_line
			(start -2.54 -1.27)
			(end 0 -1.27)
			(stroke
				(width 0.1524)
				(type default)
			)
			(layer "B.SilkS")
		)
		(fp_line
			(start 0 -1.27)
			(end 0 -0.635)
			(stroke
				(width 0.1524)
				(type default)
			)
			(layer "B.SilkS")
		)
		(fp_poly
			(pts
				(xy 2.895346 -0.6985) (xy 2.895346 0.8255) (xy 1.371346 0.0635)
			)
			(stroke
				(width 0)
				(type default)
			)
			(fill yes)
			(layer "B.SilkS")
		)
		(fp_line
			(start -2.54 3.81)
			(end -2.54 -1.27)
			(stroke
				(width 0.1)
				(type default)
			)
			(layer "B.Fab")
		)
		(fp_line
			(start 0 3.81)
			(end -2.54 3.81)
			(stroke
				(width 0.1)
				(type default)
			)
			(layer "B.Fab")
		)
		(fp_line
			(start -2.54 -1.27)
			(end 0 -1.27)
			(stroke
				(width 0.1)
				(type default)
			)
			(layer "B.Fab")
		)
		(fp_line
			(start 0 -1.27)
			(end 0 3.81)
			(stroke
				(width 0.1)
				(type default)
			)
			(layer "B.Fab")
		)
		(fp_poly
			(pts
				(xy 0.761746 0) (xy 2.285746 -0.762) (xy 2.285746 0.762)
			)
			(stroke
				(width 0)
				(type default)
			)
			(fill yes)
			(layer "B.Fab")
		)
		(pad "1" thru_hole circle
			(at 0 0 90)
			(size 1.0033 1.0033)
			(drill 0.249936)
			(layers "*.Cu" "*.Mask")
			(remove_unused_layers no)
			(net "TDR_DIFF_100_IN4_DN")
			(clearance 0.10795)
			(padstack
				(mode front_inner_back)
				(layer "Inner"
					(shape circle)
					(size 0.8001 0.8001)
					(clearance 0.1524)
				)
				(layer "B.Cu"
					(shape circle)
					(size 1.0033 1.0033)
					(thermal_gap 0.10795)
					(clearance 0.10795)
				)
			)
		)
		(pad "2" thru_hole circle
			(at -2.54 0 90)
			(size 1.9939 1.9939)
			(drill 0.249936)
			(layers "*.Cu" "*.Mask")
			(remove_unused_layers no)
			(net "T1_GND")
			(clearance 0.10795)
			(padstack
				(mode front_inner_back)
				(layer "Inner"
					(shape circle)
					(size 0.8001 0.8001)
					(clearance 0.1524)
				)
				(layer "B.Cu"
					(shape circle)
					(size 1.9939 1.9939)
					(thermal_gap 0.10795)
					(clearance 0.10795)
				)
			)
		)
		(pad "3" thru_hole circle
			(at -2.54 2.54 90)
			(size 1.9939 1.9939)
			(drill 0.249936)
			(layers "*.Cu" "*.Mask")
			(remove_unused_layers no)
			(net "T1_GND")
			(clearance 0.10795)
			(padstack
				(mode front_inner_back)
				(layer "Inner"
					(shape circle)
					(size 0.8001 0.8001)
					(clearance 0.1524)
				)
				(layer "B.Cu"
					(shape circle)
					(size 1.9939 1.9939)
					(thermal_gap 0.10795)
					(clearance 0.10795)
				)
			)
		)
		(pad "4" thru_hole circle
			(at 0 2.54 90)
			(size 1.0033 1.0033)
			(drill 0.249936)
			(layers "*.Cu" "*.Mask")
			(remove_unused_layers no)
			(net "TDR_DIFF_100_IN4_DP")
			(clearance 0.10795)
			(padstack
				(mode front_inner_back)
				(layer "Inner"
					(shape circle)
					(size 0.8001 0.8001)
					(clearance 0.1524)
				)
				(layer "B.Cu"
					(shape circle)
					(size 1.0033 1.0033)
					(thermal_gap 0.10795)
					(clearance 0.10795)
				)
			)
		)
	)
	(footprint ""
		(layer "B.Cu")
		(at 52.358544 -152.603454)
		(property "Reference" "PR1796"
			(at 0 0 0)
			(layer "B.SilkS")
			(hide yes)
			(effects
				(font
					(size 1.27 1.27)
				)
				(justify mirror)
			)
		)
		(property "Value" ""
			(at 0 0 0)
			(layer "B.Fab")
			(effects
				(font
					(size 1.27 1.27)
				)
				(justify mirror)
			)
		)
		(duplicate_pad_numbers_are_jumpers no)
		(fp_line
			(start -0.7874 -0.4064)
			(end -0.7874 0.4064)
			(stroke
				(width 0.1524)
				(type default)
			)
			(layer "B.SilkS")
		)
		(fp_line
			(start -0.7874 0.4064)
			(end 0.7874 0.4064)
			(stroke
				(width 0.1524)
				(type default)
			)
			(layer "B.SilkS")
		)
		(fp_line
			(start 0.7874 -0.4064)
			(end -0.7874 -0.4064)
			(stroke
				(width 0.1524)
				(type default)
			)
			(layer "B.SilkS")
		)
		(fp_line
			(start 0.7874 0.4064)
			(end 0.7874 -0.4064)
			(stroke
				(width 0.1524)
				(type default)
			)
			(layer "B.SilkS")
		)
		(fp_line
			(start -0.67945 -0.3048)
			(end -0.67945 0.3048)
			(stroke
				(width 0.1)
				(type default)
			)
			(layer "B.Fab")
		)
		(fp_line
			(start -0.67945 0.3048)
			(end -0.120396 0.3048)
			(stroke
				(width 0.1)
				(type default)
			)
			(layer "B.Fab")
		)
		(fp_line
			(start -0.12065 -0.3048)
			(end -0.67945 -0.3048)
			(stroke
				(width 0.1)
				(type default)
			)
			(layer "B.Fab")
		)
		(fp_line
			(start -0.12065 -0.2794)
			(end -0.12065 -0.3048)
			(stroke
				(width 0.1)
				(type default)
			)
			(layer "B.Fab")
		)
		(fp_line
			(start -0.120396 0.2794)
			(end 0.12065 0.2794)
			(stroke
				(width 0.1)
				(type default)
			)
			(layer "B.Fab")
		)
		(fp_line
			(start -0.120396 0.3048)
			(end -0.120396 0.2794)
			(stroke
				(width 0.1)
				(type default)
			)
			(layer "B.Fab")
		)
		(fp_line
			(start 0.12065 -0.305054)
			(end 0.12065 -0.2794)
			(stroke
				(width 0.1)
				(type default)
			)
			(layer "B.Fab")
		)
		(fp_line
			(start 0.12065 -0.2794)
			(end -0.12065 -0.2794)
			(stroke
				(width 0.1)
				(type default)
			)
			(layer "B.Fab")
		)
		(fp_line
			(start 0.12065 0.2794)
			(end 0.12065 0.3048)
			(stroke
				(width 0.1)
				(type default)
			)
			(layer "B.Fab")
		)
		(fp_line
			(start 0.12065 0.3048)
			(end 0.67945 0.3048)
			(stroke
				(width 0.1)
				(type default)
			)
			(layer "B.Fab")
		)
		(fp_line
			(start 0.67945 -0.305054)
			(end 0.12065 -0.305054)
			(stroke
				(width 0.1)
				(type default)
			)
			(layer "B.Fab")
		)
		(fp_line
			(start 0.67945 0.3048)
			(end 0.67945 -0.305054)
			(stroke
				(width 0.1)
				(type default)
			)
			(layer "B.Fab")
		)
		(pad "1" smd circle
			(at 0.40005 0 180)
			(size 0 0)
			(layers "B.Cu" "B.Mask" "B.Paste")
			(net "PVCCINFAON_CPU1_VOS1")
		)
		(pad "2" smd circle
			(at -0.40005 0 180)
			(size 0 0)
			(layers "B.Cu" "B.Mask" "B.Paste")
			(net "PVCCINFAON_CPU1")
		)
	)
	(footprint ""
		(layer "B.Cu")
		(at 143.793718 -337.86318)
		(property "Reference" "C1392"
			(at 0 0 0)
			(layer "B.SilkS")
			(hide yes)
			(effects
				(font
					(size 1.27 1.27)
				)
				(justify mirror)
			)
		)
		(property "Value" ""
			(at 0 0 0)
			(layer "B.Fab")
			(effects
				(font
					(size 1.27 1.27)
				)
				(justify mirror)
			)
		)
		(duplicate_pad_numbers_are_jumpers no)
		(fp_line
			(start -1.524 -0.762)
			(end -1.524 0.762)
			(stroke
				(width 0.1524)
				(type default)
			)
			(layer "B.SilkS")
		)
		(fp_line
			(start -1.524 0.762)
			(end 1.524 0.762)
			(stroke
				(width 0.1524)
				(type default)
			)
			(layer "B.SilkS")
		)
		(fp_line
			(start 1.524 -0.762)
			(end -1.524 -0.762)
			(stroke
				(width 0.1524)
				(type default)
			)
			(layer "B.SilkS")
		)
		(fp_line
			(start 1.524 0.762)
			(end 1.524 -0.762)
			(stroke
				(width 0.1524)
				(type default)
			)
			(layer "B.SilkS")
		)
		(fp_line
			(start -1.1049 -0.724916)
			(end 1.1049 -0.724916)
			(stroke
				(width 0.1)
				(type default)
			)
			(layer "B.Fab")
		)
		(fp_line
			(start -1.1049 0.724916)
			(end -1.1049 -0.724916)
			(stroke
				(width 0.1)
				(type default)
			)
			(layer "B.Fab")
		)
		(fp_line
			(start 1.1049 -0.724916)
			(end 1.1049 0.724916)
			(stroke
				(width 0.1)
				(type default)
			)
			(layer "B.Fab")
		)
		(fp_line
			(start 1.1049 0.724916)
			(end -1.1049 0.724916)
			(stroke
				(width 0.1)
				(type default)
			)
			(layer "B.Fab")
		)
		(pad "1" smd rect
			(at 0.889 0)
			(size 1.016 1.27)
			(layers "B.Cu" "B.Mask" "B.Paste")
			(net "PVPP_HBM_CPU1")
		)
		(pad "2" smd rect
			(at -0.889 0)
			(size 1.016 1.27)
			(layers "B.Cu" "B.Mask" "B.Paste")
			(net "GND")
		)
	)
	(footprint ""
		(layer "B.Cu")
		(at 348.770194 -54.496208 90)
		(property "Reference" "C1261"
			(at 0 0 90)
			(layer "B.SilkS")
			(hide yes)
			(effects
				(font
					(size 1.27 1.27)
				)
				(justify mirror)
			)
		)
		(property "Value" ""
			(at 0 0 90)
			(layer "B.Fab")
			(effects
				(font
					(size 1.27 1.27)
				)
				(justify mirror)
			)
		)
		(duplicate_pad_numbers_are_jumpers no)
		(fp_line
			(start 1.2954 -0.5842)
			(end -1.2954 -0.5842)
			(stroke
				(width 0.1524)
				(type default)
			)
			(layer "B.SilkS")
		)
		(fp_line
			(start 0 -0.5842)
			(end 0 0.5842)
			(stroke
				(width 0.1524)
				(type default)
			)
			(layer "B.SilkS")
		)
		(fp_line
			(start -1.2954 -0.5842)
			(end -1.2954 0.5842)
			(stroke
				(width 0.1524)
				(type default)
			)
			(layer "B.SilkS")
		)
		(fp_line
			(start 1.2954 0.5842)
			(end 1.2954 -0.5842)
			(stroke
				(width 0.1524)
				(type default)
			)
			(layer "B.SilkS")
		)
		(fp_line
			(start -1.2954 0.5842)
			(end 1.2954 0.5842)
			(stroke
				(width 0.1524)
				(type default)
			)
			(layer "B.SilkS")
		)
		(fp_line
			(start 0.8636 -0.4572)
			(end -0.8636 -0.4572)
			(stroke
				(width 0.1)
				(type default)
			)
			(layer "B.Fab")
		)
		(fp_line
			(start -0.8636 -0.4572)
			(end -0.8636 -0.4064)
			(stroke
				(width 0.1)
				(type default)
			)
			(layer "B.Fab")
		)
		(fp_line
			(start 1.1938 -0.4064)
			(end 0.8636 -0.4064)
			(stroke
				(width 0.1)
				(type default)
			)
			(layer "B.Fab")
		)
		(fp_line
			(start 0.8636 -0.4064)
			(end 0.8636 -0.4572)
			(stroke
				(width 0.1)
				(type default)
			)
			(layer "B.Fab")
		)
		(fp_line
			(start -0.8636 -0.4064)
			(end -1.1938 -0.4064)
			(stroke
				(width 0.1)
				(type default)
			)
			(layer "B.Fab")
		)
		(fp_line
			(start -1.1938 -0.4064)
			(end -1.1938 0.4064)
			(stroke
				(width 0.1)
				(type default)
			)
			(layer "B.Fab")
		)
		(fp_line
			(start 1.1938 0.4064)
			(end 1.1938 -0.4064)
			(stroke
				(width 0.1)
				(type default)
			)
			(layer "B.Fab")
		)
		(fp_line
			(start 0.8636 0.4064)
			(end 1.1938 0.4064)
			(stroke
				(width 0.1)
				(type default)
			)
			(layer "B.Fab")
		)
		(fp_line
			(start -0.8636 0.4064)
			(end -0.8636 0.4572)
			(stroke
				(width 0.1)
				(type default)
			)
			(layer "B.Fab")
		)
		(fp_line
			(start -1.1938 0.4064)
			(end -0.8636 0.4064)
			(stroke
				(width 0.1)
				(type default)
			)
			(layer "B.Fab")
		)
		(fp_line
			(start 0.8636 0.4572)
			(end 0.8636 0.4064)
			(stroke
				(width 0.1)
				(type default)
			)
			(layer "B.Fab")
		)
		(fp_line
			(start -0.8636 0.4572)
			(end 0.8636 0.4572)
			(stroke
				(width 0.1)
				(type default)
			)
			(layer "B.Fab")
		)
		(pad "1" smd rect
			(at 0.7366 0)
			(size 0.7112 0.8128)
			(layers "B.Cu" "B.Mask" "B.Paste")
			(net "P1V8_PCH_PLL_AUX")
		)
		(pad "2" smd rect
			(at -0.7366 0)
			(size 0.7112 0.8128)
			(layers "B.Cu" "B.Mask" "B.Paste")
			(net "GND")
		)
	)
	(footprint ""
		(layer "B.Cu")
		(at 31.396432 -169.5958 180)
		(property "Reference" "PR220"
			(at 0 0 0)
			(layer "B.SilkS")
			(hide yes)
			(effects
				(font
					(size 1.27 1.27)
				)
				(justify mirror)
			)
		)
		(property "Value" ""
			(at 0 0 0)
			(layer "B.Fab")
			(effects
				(font
					(size 1.27 1.27)
				)
				(justify mirror)
			)
		)
		(duplicate_pad_numbers_are_jumpers no)
		(fp_line
			(start 0.7874 0.4064)
			(end 0.7874 -0.4064)
			(stroke
				(width 0.1524)
				(type default)
			)
			(layer "B.SilkS")
		)
		(fp_line
			(start 0.7874 -0.4064)
			(end -0.7874 -0.4064)
			(stroke
				(width 0.1524)
				(type default)
			)
			(layer "B.SilkS")
		)
		(fp_line
			(start -0.7874 0.4064)
			(end 0.7874 0.4064)
			(stroke
				(width 0.1524)
				(type default)
			)
			(layer "B.SilkS")
		)
		(fp_line
			(start -0.7874 -0.4064)
			(end -0.7874 0.4064)
			(stroke
				(width 0.1524)
				(type default)
			)
			(layer "B.SilkS")
		)
		(fp_line
			(start 0.67945 0.3048)
			(end 0.67945 -0.305054)
			(stroke
				(width 0.1)
				(type default)
			)
			(layer "B.Fab")
		)
		(fp_line
			(start 0.67945 -0.305054)
			(end 0.12065 -0.305054)
			(stroke
				(width 0.1)
				(type default)
			)
			(layer "B.Fab")
		)
		(fp_line
			(start 0.12065 0.3048)
			(end 0.67945 0.3048)
			(stroke
				(width 0.1)
				(type default)
			)
			(layer "B.Fab")
		)
		(fp_line
			(start 0.12065 0.2794)
			(end 0.12065 0.3048)
			(stroke
				(width 0.1)
				(type default)
			)
			(layer "B.Fab")
		)
		(fp_line
			(start 0.12065 -0.2794)
			(end -0.12065 -0.2794)
			(stroke
				(width 0.1)
				(type default)
			)
			(layer "B.Fab")
		)
		(fp_line
			(start 0.12065 -0.305054)
			(end 0.12065 -0.2794)
			(stroke
				(width 0.1)
				(type default)
			)
			(layer "B.Fab")
		)
		(fp_line
			(start -0.120396 0.3048)
			(end -0.120396 0.2794)
			(stroke
				(width 0.1)
				(type default)
			)
			(layer "B.Fab")
		)
		(fp_line
			(start -0.120396 0.2794)
			(end 0.12065 0.2794)
			(stroke
				(width 0.1)
				(type default)
			)
			(layer "B.Fab")
		)
		(fp_line
			(start -0.12065 -0.2794)
			(end -0.12065 -0.3048)
			(stroke
				(width 0.1)
				(type default)
			)
			(layer "B.Fab")
		)
		(fp_line
			(start -0.12065 -0.3048)
			(end -0.67945 -0.3048)
			(stroke
				(width 0.1)
				(type default)
			)
			(layer "B.Fab")
		)
		(fp_line
			(start -0.67945 0.3048)
			(end -0.120396 0.3048)
			(stroke
				(width 0.1)
				(type default)
			)
			(layer "B.Fab")
		)
		(fp_line
			(start -0.67945 -0.3048)
			(end -0.67945 0.3048)
			(stroke
				(width 0.1)
				(type default)
			)
			(layer "B.Fab")
		)
		(pad "1" smd circle
			(at 0.40005 0)
			(size 0 0)
			(layers "B.Cu" "B.Mask" "B.Paste")
			(net "PVCCD_HV_CPU1_VCC")
		)
		(pad "2" smd circle
			(at -0.40005 0)
			(size 0 0)
			(layers "B.Cu" "B.Mask" "B.Paste")
			(net "P3V3_AUX")
		)
	)
)
